# BASEBOARD_FAB2 (Tioga Pass) — schematic netlist excerpt (pin names and nets, part order shuffled) for the footprints in the layout excerpt that follows; sources: Cadence DE-HDL packaged netlist, KiCad conversion of Wiwynn_Tioga_Pass_MB.brd

J6L2  SCONN288_H44441003  SCONN  pkg PIP  page 52
  \12v\(1)  = P12V_NVDIMM_DEF
  VSS(93)  = GND
  DQ(4)  = M_E_DQ<4>
  VSS(92)  = GND
  DQ(0)  = M_E_DQ<0>
  VSS(91)  = GND
  DQS9P  = M_E_DQS_DP<9>
  DQS9N  = M_E_DQS_DN<9>
  VSS(90)  = GND
  DQ(6)  = M_E_DQ<6>
  VSS(89)  = GND
  DQ(2)  = M_E_DQ<2>
  VSS(88)  = GND
  DQ(12)  = M_E_DQ<12>
  VSS(87)  = GND
  DQ(8)  = M_E_DQ<8>
  VSS(86)  = GND
  DQS10P  = M_E_DQS_DP<10>
  DQS10N  = M_E_DQS_DN<10>
  VSS(85)  = GND
  DQ(14)  = M_E_DQ<14>
  VSS(84)  = GND
  DQ(10)  = M_E_DQ<10>
  VSS(83)  = GND
  DQ(20)  = M_E_DQ<20>
  VSS(82)  = GND
  DQ(16)  = M_E_DQ<16>
  VSS(81)  = GND
  DQS11P  = M_E_DQS_DP<11>
  DQS11N  = M_E_DQS_DN<11>
  VSS(80)  = GND
  DQ(22)  = M_E_DQ<22>
  VSS(79)  = GND
  DQ(18)  = M_E_DQ<18>
  VSS(78)  = GND
  DQ(28)  = M_E_DQ<28>
  VSS(77)  = GND
  DQ(24)  = M_E_DQ<24>
  VSS(76)  = GND
  DQS12P  = M_E_DQS_DP<12>
  DQS12N  = M_E_DQS_DN<12>
  VSS(75)  = GND
  DQ(30)  = M_E_DQ<30>
  VSS(74)  = GND
  DQ(26)  = M_E_DQ<26>
  VSS(73)  = GND
  CB(4)  = M_E_ECC<4>
  VSS(72)  = GND
  CB(0)  = M_E_ECC<0>
  VSS(71)  = GND
  DQS17P  = M_E_DQS_DP<17>
  DQS17N  = M_E_DQS_DN<17>
  VSS(70)  = GND
  CB(6)  = M_E_ECC<6>
  VSS(69)  = GND
  CB(2)  = M_E_ECC<2>
  VSS(68)  = GND
  RESET_N  = M_DEF_RST_N
  VDD(25)  = PVDDQ_DEF
  CKE(0)  = M_E_CKE<2>
  VDD(24)  = PVDDQ_DEF
  ACT_N  = M_E_ACT_N
  BG(0)  = M_E_BG<0>
  VDD(23)  = PVDDQ_DEF
  A12  = M_E_MA<12>
  A9  = M_E_MA<9>
  VDD(22)  = PVDDQ_DEF
  A8  = M_E_MA<8>
  A6  = M_E_MA<6>
  VDD(21)  = PVDDQ_DEF
  A3  = M_E_MA<3>
  A1  = M_E_MA<1>
  VDD(20)  = PVDDQ_DEF
  CK0P  = M_E_CLK_DP<2>
  CK0N  = M_E_CLK_DN<2>
  VDD(19)  = PVDDQ_DEF
  VTT(1)  = PVTT_DEF
  EVENT_N  = FM_DIMM_EVENT_COD_N
  A0  = M_E_MA<0>
  VDD(18)  = PVDDQ_DEF
  BA(0)  = M_E_BA<0>
  A16_RAS_N  = M_E_MA<16>
  VDD(17)  = PVDDQ_DEF
  S0_N  = M_E_CS_N<4>
  VDD(16)  = PVDDQ_DEF
  A15_CAS_N  = M_E_MA<15>
  ODT(0)  = M_E_ODT<2>
  VDD(15)  = PVDDQ_DEF
  S1_N  = M_E_CS_N<5>
  VDD(14)  = PVDDQ_DEF
  ODT(1)  = M_E_ODT<3>
  VDD(13)  = PVDDQ_DEF
  S2_N_C(0)  = M_E_CS_N<6>
  VSS(67)  = GND
  DQ(36)  = M_E_DQ<36>
  VSS(66)  = GND
  DQ(32)  = M_E_DQ<32>
  VSS(65)  = GND
  DQS13P  = M_E_DQS_DP<13>
  DQS13N  = M_E_DQS_DN<13>
  VSS(64)  = GND
  DQ(38)  = M_E_DQ<38>
  VSS(63)  = GND
  DQ(34)  = M_E_DQ<34>
  VSS(62)  = GND
  DQ(44)  = M_E_DQ<44>
  VSS(61)  = GND
  DQ(40)  = M_E_DQ<40>
  VSS(60)  = GND
  DQS14P  = M_E_DQS_DP<14>
  DQS14N  = M_E_DQS_DN<14>
  VSS(59)  = GND
  DQ(46)  = M_E_DQ<46>
  VSS(58)  = GND
  DQ(42)  = M_E_DQ<42>
  VSS(57)  = GND
  DQ(52)  = M_E_DQ<52>
  VSS(56)  = GND
  DQ(48)  = M_E_DQ<48>
  VSS(55)  = GND
  DQS15P  = M_E_DQS_DP<15>
  DQS15N  = M_E_DQS_DN<15>
  VSS(54)  = GND
  DQ(54)  = M_E_DQ<54>
  VSS(53)  = GND
  DQ(50)  = M_E_DQ<50>
  VSS(52)  = GND
  DQ(60)  = M_E_DQ<60>
  VSS(51)  = GND
  DQ(56)  = M_E_DQ<56>
  VSS(50)  = GND
  DQS16P  = M_E_DQS_DP<16>
  DQS16N  = M_E_DQS_DN<16>
  VSS(49)  = GND
  DQ(62)  = M_E_DQ<62>
  VSS(48)  = GND
  DQ(58)  = M_E_DQ<58>
  VSS(47)  = GND
  SA(0)  = PVPP_DEF
  SA(1)  = PVPP_DEF
  SCL  = SMB_DDR_DEF_VPP_SCL
  VPP(4)  = PVPP_DEF
  VPP(3)  = PVPP_DEF
  RFU(2)  = TP_CH_E_DIMM_E1_RFU_2
  \12v\(0)  = P12V_NVDIMM_DEF
  VREFCA  = M_E_VREF
  VSS(46)  = GND
  DQ(5)  = M_E_DQ<5>
  VSS(45)  = GND
  DQ(1)  = M_E_DQ<1>
  VSS(44)  = GND
  DQS0N  = M_E_DQS_DN<0>
  DQS0P  = M_E_DQS_DP<0>
  VSS(43)  = GND
  DQ(7)  = M_E_DQ<7>
  VSS(42)  = GND
  DQ(3)  = M_E_DQ<3>
  VSS(41)  = GND
  DQ(13)  = M_E_DQ<13>
  VSS(40)  = GND
  DQ(9)  = M_E_DQ<9>
  VSS(39)  = GND
  DQS1N  = M_E_DQS_DN<1>
  DQS1P  = M_E_DQS_DP<1>
  VSS(38)  = GND
  DQ(15)  = M_E_DQ<15>
  VSS(37)  = GND
  DQ(11)  = M_E_DQ<11>
  VSS(36)  = GND
  DQ(21)  = M_E_DQ<21>
  VSS(35)  = GND
  DQ(17)  = M_E_DQ<17>
  VSS(34)  = GND
  DQS2N  = M_E_DQS_DN<2>
  DQS2P  = M_E_DQS_DP<2>
  VSS(33)  = GND
  DQ(23)  = M_E_DQ<23>
  VSS(32)  = GND
  DQ(19)  = M_E_DQ<19>
  VSS(31)  = GND
  DQ(29)  = M_E_DQ<29>
  VSS(30)  = GND
  DQ(25)  = M_E_DQ<25>
  VSS(29)  = GND
  DQS3N  = M_E_DQS_DN<3>
  DQS3P  = M_E_DQS_DP<3>
  VSS(28)  = GND
  DQ(31)  = M_E_DQ<31>
  VSS(27)  = GND
  DQ(27)  = M_E_DQ<27>
  VSS(26)  = GND
  CB(5)  = M_E_ECC<5>
  VSS(25)  = GND
  CB(1)  = M_E_ECC<1>
  VSS(24)  = GND
  DQS8N  = M_E_DQS_DN<8>
  DQS8P  = M_E_DQS_DP<8>
  VSS(23)  = GND
  CB(7)  = M_E_ECC<7>
  VSS(22)  = GND
  CB(3)  = M_E_ECC<3>
  VSS(21)  = GND
  CKE(1)  = M_E_CKE<3>
  VDD(12)  = PVDDQ_DEF
  RFU(0)  = TP_CH_E_DIMM_E1_RFU_0
  VDD(11)  = PVDDQ_DEF
  BG(1)  = M_E_BG<1>
  ALERT_N  = M_E_ALERT_N
  VDD(10)  = PVDDQ_DEF
  A11  = M_E_MA<11>
  A7  = M_E_MA<7>
  VDD(9)  = PVDDQ_DEF
  A5  = M_E_MA<5>
  A4  = M_E_MA<4>
  VDD(8)  = PVDDQ_DEF
  A2  = M_E_MA<2>
  VDD(7)  = PVDDQ_DEF
  CK1P  = M_E_CLK_DP<3>
  CK1N  = M_E_CLK_DN<3>
  VDD(6)  = PVDDQ_DEF
  VTT(0)  = PVTT_DEF
  PAR  = M_E_PAR
  VDD(5)  = PVDDQ_DEF
  BA(1)  = M_E_BA<1>
  A10  = M_E_MA<10>
  VDD(4)  = PVDDQ_DEF
  RFU(1)  = TP_CH_E_DIMM_E1_RFU_1
  A14_WE_N  = M_E_MA<14>
  VDD(3)  = PVDDQ_DEF
  SAVE_N_NC  = FM_ADR_COMPLETE_DEF_N
  VDD(2)  = PVDDQ_DEF
  A13  = M_E_MA<13>
  VDD(1)  = PVDDQ_DEF
  A17  = M_E_MA<17>
  C(2)  = M_E_C<2>
  VDD(0)  = PVDDQ_DEF
  S3_N_C(1)  = M_E_CS_N<7>
  SA(2)  = GND
  VSS(20)  = GND
  DQ(37)  = M_E_DQ<37>
  VSS(19)  = GND
  DQ(33)  = M_E_DQ<33>
  VSS(18)  = GND
  DQS4N  = M_E_DQS_DN<4>
  DQS4P  = M_E_DQS_DP<4>
  VSS(17)  = GND
  DQ(39)  = M_E_DQ<39>
  VSS(16)  = GND
  DQ(35)  = M_E_DQ<35>
  VSS(15)  = GND
  DQ(45)  = M_E_DQ<45>
  VSS(14)  = GND
  DQ(41)  = M_E_DQ<41>
  VSS(13)  = GND
  DQS5N  = M_E_DQS_DN<5>
  DQS5P  = M_E_DQS_DP<5>
  VSS(12)  = GND
  DQ(47)  = M_E_DQ<47>
  VSS(11)  = GND
  DQ(43)  = M_E_DQ<43>
  VSS(10)  = GND
  DQ(53)  = M_E_DQ<53>
  VSS(9)  = GND
  DQ(49)  = M_E_DQ<49>
  VSS(8)  = GND
  DQS6N  = M_E_DQS_DN<6>
  DQS6P  = M_E_DQS_DP<6>
  VSS(7)  = GND
  DQ(55)  = M_E_DQ<55>
  VSS(6)  = GND
  DQ(51)  = M_E_DQ<51>
  VSS(5)  = GND
  DQ(61)  = M_E_DQ<61>
  VSS(4)  = GND
  DQ(57)  = M_E_DQ<57>
  VSS(3)  = GND
  DQS7N  = M_E_DQS_DN<7>
  DQS7P  = M_E_DQS_DP<7>
  VSS(2)  = GND
  DQ(63)  = M_E_DQ<63>
  VSS(1)  = GND
  DQ(59)  = M_E_DQ<59>
  VSS(0)  = GND
  VDDSPD  = PVPP_DEF
  SDA  = SMB_DDR_DEF_VPP_SDA
  VPP(1)  = PVPP_DEF
  VPP(0)  = PVPP_DEF
  VPP(2)  = PVPP_DEF

(kicad_pcb
	(version 20260206)
	(generator "pcbnew")
	(generator_version "10.0")
	(general
		(thickness 1.6)
		(legacy_teardrops no)
	)
	(paper "A4")
	(title_block
		(title "Wiwynn_Tioga_Pass_MB.brd")
		(comment 1 "Tioga Pass / footprint 3319 of 4770 (J6L2), pads 202-249 of 291")
	)
	(layers
		(0 "F.Cu" signal "TOP")
		(4 "In1.Cu" signal "L2GND")
		(6 "In2.Cu" signal "L3")
		(8 "In3.Cu" signal "L4GND")
		(10 "In4.Cu" signal "L5")
		(12 "In5.Cu" signal "L6GND")
		(14 "In6.Cu" signal "L7VCC")
		(16 "In7.Cu" signal "L8VCC")
		(18 "In8.Cu" signal "L9GND")
		(20 "In9.Cu" signal "L10")
		(22 "In10.Cu" signal "L11GND")
		(24 "In11.Cu" signal "L12")
		(26 "In12.Cu" signal "L13GND")
		(2 "B.Cu" signal "BOTTOM")
		(9 "F.Adhes" user "F.Adhesive")
		(11 "B.Adhes" user "B.Adhesive")
		(13 "F.Paste" user "Package Geometry/Pastemask Top")
		(15 "B.Paste" user "Package Geometry/Pastemask Bottom")
		(5 "F.SilkS" user "Ref Des/Silkscreen Top")
		(7 "B.SilkS" user "Ref Des/Silkscreen Bottom")
		(1 "F.Mask" user "Board Geometry/Soldermask Top")
		(3 "B.Mask" user "Board Geometry/Soldermask Bottom")
		(17 "Dwgs.User" user "User.Drawings")
		(19 "Cmts.User" user "User.Comments")
		(21 "Eco1.User" user "User.Eco1")
		(23 "Eco2.User" user "User.Eco2")
		(25 "Edge.Cuts" user "Board Geometry/Outline")
		(27 "Margin" user)
		(31 "F.CrtYd" user "Package Geometry/Place Bound Top")
		(29 "B.CrtYd" user "Package Geometry/Place Bound Bottom")
		(35 "F.Fab" user "Ref Des/Assembly Top")
		(33 "B.Fab" user "Ref Des/Assembly Bottom")
	)
	(footprint ""
		(layer "B.Cu")
		(at 194.700398 -142.477236 90)
		(property "Reference" "J6L2"
			(at 2.276348 38.21811 0)
			(unlocked yes)
			(layer "B.SilkS")
			(effects
				(font
					(size 0.7874 0.5842)
					(thickness 0.1524)
				)
				(justify left mirror)
			)
		)
		(property "Value" ""
			(at 0 0 90)
			(layer "B.Fab")
			(effects
				(font
					(size 1.27 1.27)
				)
				(justify mirror)
			)
		)
		(duplicate_pad_numbers_are_jumpers no)
		(pad "199" smd rect
			(at -4.59994 45.900086 270)
			(size 1.8034 0.508)
			(layers "B.Cu" "B.Mask" "B.Paste")
			(net "M_E_ECC<7>")
		)
		(pad "200" smd rect
			(at -4.59994 46.74997 270)
			(size 1.8034 0.508)
			(layers "B.Cu" "B.Mask" "B.Paste")
			(net "GND")
		)
		(pad "201" smd rect
			(at -4.59994 47.600108 270)
			(size 1.8034 0.508)
			(layers "B.Cu" "B.Mask" "B.Paste")
			(net "M_E_ECC<3>")
		)
		(pad "202" smd rect
			(at -4.59994 48.449992 270)
			(size 1.8034 0.508)
			(layers "B.Cu" "B.Mask" "B.Paste")
			(net "GND")
		)
		(pad "203" smd rect
			(at -4.59994 49.299876 270)
			(size 1.8034 0.508)
			(layers "B.Cu" "B.Mask" "B.Paste")
			(net "M_E_CKE<3>")
		)
		(pad "204" smd rect
			(at -4.59994 50.150014 270)
			(size 1.8034 0.508)
			(layers "B.Cu" "B.Mask" "B.Paste")
			(net "PVDDQ_DEF")
		)
		(pad "205" smd rect
			(at -4.59994 50.999898 270)
			(size 1.8034 0.508)
			(layers "B.Cu" "B.Mask" "B.Paste")
			(net "TP_CH_E_DIMM_E1_RFU_0")
		)
		(pad "206" smd rect
			(at -4.59994 51.850036 270)
			(size 1.8034 0.508)
			(layers "B.Cu" "B.Mask" "B.Paste")
			(net "PVDDQ_DEF")
		)
		(pad "207" smd rect
			(at -4.59994 52.69992 270)
			(size 1.8034 0.508)
			(layers "B.Cu" "B.Mask" "B.Paste")
			(net "M_E_BG<1>")
		)
		(pad "208" smd rect
			(at -4.59994 53.550058 270)
			(size 1.8034 0.508)
			(layers "B.Cu" "B.Mask" "B.Paste")
			(net "M_E_ALERT_N")
		)
		(pad "209" smd rect
			(at -4.59994 54.399942 270)
			(size 1.8034 0.508)
			(layers "B.Cu" "B.Mask" "B.Paste")
			(net "PVDDQ_DEF")
		)
		(pad "210" smd rect
			(at -4.59994 55.25008 270)
			(size 1.8034 0.508)
			(layers "B.Cu" "B.Mask" "B.Paste")
			(net "M_E_MA<11>")
		)
		(pad "211" smd rect
			(at -4.59994 56.099964 270)
			(size 1.8034 0.508)
			(layers "B.Cu" "B.Mask" "B.Paste")
			(net "M_E_MA<7>")
		)
		(pad "212" smd rect
			(at -4.59994 56.950102 270)
			(size 1.8034 0.508)
			(layers "B.Cu" "B.Mask" "B.Paste")
			(net "PVDDQ_DEF")
		)
		(pad "213" smd rect
			(at -4.59994 57.799986 270)
			(size 1.8034 0.508)
			(layers "B.Cu" "B.Mask" "B.Paste")
			(net "M_E_MA<5>")
		)
		(pad "214" smd rect
			(at -4.59994 58.650124 270)
			(size 1.8034 0.508)
			(layers "B.Cu" "B.Mask" "B.Paste")
			(net "M_E_MA<4>")
		)
		(pad "215" smd rect
			(at -4.59994 59.500008 270)
			(size 1.8034 0.508)
			(layers "B.Cu" "B.Mask" "B.Paste")
			(net "PVDDQ_DEF")
		)
		(pad "216" smd rect
			(at -4.59994 60.349892 270)
			(size 1.8034 0.508)
			(layers "B.Cu" "B.Mask" "B.Paste")
			(net "M_E_MA<2>")
		)
		(pad "217" smd rect
			(at -4.59994 61.20003 270)
			(size 1.8034 0.508)
			(layers "B.Cu" "B.Mask" "B.Paste")
			(net "PVDDQ_DEF")
		)
		(pad "218" smd rect
			(at -4.59994 62.049914 270)
			(size 1.8034 0.508)
			(layers "B.Cu" "B.Mask" "B.Paste")
			(net "M_E_CLK_DP<3>")
		)
		(pad "219" smd rect
			(at -4.59994 62.900052 270)
			(size 1.8034 0.508)
			(layers "B.Cu" "B.Mask" "B.Paste")
			(net "M_E_CLK_DN<3>")
		)
		(pad "220" smd rect
			(at -4.59994 63.749936 270)
			(size 1.8034 0.508)
			(layers "B.Cu" "B.Mask" "B.Paste")
			(net "PVDDQ_DEF")
		)
		(pad "221" smd rect
			(at -4.59994 64.600074 270)
			(size 1.8034 0.508)
			(layers "B.Cu" "B.Mask" "B.Paste")
			(net "PVTT_DEF")
		)
		(pad "222" smd rect
			(at -4.59994 70.550024 270)
			(size 1.8034 0.508)
			(layers "B.Cu" "B.Mask" "B.Paste")
			(net "M_E_PAR")
		)
		(pad "223" smd rect
			(at -4.59994 71.399908 270)
			(size 1.8034 0.508)
			(layers "B.Cu" "B.Mask" "B.Paste")
			(net "PVDDQ_DEF")
		)
		(pad "224" smd rect
			(at -4.59994 72.250046 270)
			(size 1.8034 0.508)
			(layers "B.Cu" "B.Mask" "B.Paste")
			(net "M_E_BA<1>")
		)
		(pad "225" smd rect
			(at -4.59994 73.09993 270)
			(size 1.8034 0.508)
			(layers "B.Cu" "B.Mask" "B.Paste")
			(net "M_E_MA<10>")
		)
		(pad "226" smd rect
			(at -4.59994 73.950068 270)
			(size 1.8034 0.508)
			(layers "B.Cu" "B.Mask" "B.Paste")
			(net "PVDDQ_DEF")
		)
		(pad "227" smd rect
			(at -4.59994 74.799952 270)
			(size 1.8034 0.508)
			(layers "B.Cu" "B.Mask" "B.Paste")
			(net "TP_CH_E_DIMM_E1_RFU_1")
		)
		(pad "228" smd rect
			(at -4.59994 75.65009 270)
			(size 1.8034 0.508)
			(layers "B.Cu" "B.Mask" "B.Paste")
			(net "M_E_MA<14>")
		)
		(pad "229" smd rect
			(at -4.59994 76.499974 270)
			(size 1.8034 0.508)
			(layers "B.Cu" "B.Mask" "B.Paste")
			(net "PVDDQ_DEF")
		)
		(pad "230" smd rect
			(at -4.59994 77.350112 270)
			(size 1.8034 0.508)
			(layers "B.Cu" "B.Mask" "B.Paste")
			(net "FM_ADR_COMPLETE_DEF_N")
		)
		(pad "231" smd rect
			(at -4.59994 78.199996 270)
			(size 1.8034 0.508)
			(layers "B.Cu" "B.Mask" "B.Paste")
			(net "PVDDQ_DEF")
		)
		(pad "232" smd rect
			(at -4.59994 79.04988 270)
			(size 1.8034 0.508)
			(layers "B.Cu" "B.Mask" "B.Paste")
			(net "M_E_MA<13>")
		)
		(pad "233" smd rect
			(at -4.59994 79.900018 270)
			(size 1.8034 0.508)
			(layers "B.Cu" "B.Mask" "B.Paste")
			(net "PVDDQ_DEF")
		)
		(pad "234" smd rect
			(at -4.59994 80.749902 270)
			(size 1.8034 0.508)
			(layers "B.Cu" "B.Mask" "B.Paste")
			(net "M_E_MA<17>")
		)
		(pad "235" smd rect
			(at -4.59994 81.60004 270)
			(size 1.8034 0.508)
			(layers "B.Cu" "B.Mask" "B.Paste")
			(net "M_E_C<2>")
		)
		(pad "236" smd rect
			(at -4.59994 82.449924 270)
			(size 1.8034 0.508)
			(layers "B.Cu" "B.Mask" "B.Paste")
			(net "PVDDQ_DEF")
		)
		(pad "237" smd rect
			(at -4.59994 83.300062 270)
			(size 1.8034 0.508)
			(layers "B.Cu" "B.Mask" "B.Paste")
			(net "M_E_CS_N<7>")
		)
		(pad "238" smd rect
			(at -4.59994 84.149946 270)
			(size 1.8034 0.508)
			(layers "B.Cu" "B.Mask" "B.Paste")
			(net "GND")
		)
		(pad "239" smd rect
			(at -4.59994 85.000084 270)
			(size 1.8034 0.508)
			(layers "B.Cu" "B.Mask" "B.Paste")
			(net "GND")
		)
		(pad "240" smd rect
			(at -4.59994 85.849968 270)
			(size 1.8034 0.508)
			(layers "B.Cu" "B.Mask" "B.Paste")
			(net "M_E_DQ<37>")
		)
		(pad "241" smd rect
			(at -4.59994 86.700106 270)
			(size 1.8034 0.508)
			(layers "B.Cu" "B.Mask" "B.Paste")
			(net "GND")
		)
		(pad "242" smd rect
			(at -4.59994 87.54999 270)
			(size 1.8034 0.508)
			(layers "B.Cu" "B.Mask" "B.Paste")
			(net "M_E_DQ<33>")
		)
		(pad "243" smd rect
			(at -4.59994 88.399874 270)
			(size 1.8034 0.508)
			(layers "B.Cu" "B.Mask" "B.Paste")
			(net "GND")
		)
		(pad "244" smd rect
			(at -4.59994 89.250012 270)
			(size 1.8034 0.508)
			(layers "B.Cu" "B.Mask" "B.Paste")
			(net "M_E_DQS_DN<4>")
		)
		(pad "245" smd rect
			(at -4.59994 90.099896 270)
			(size 1.8034 0.508)
			(layers "B.Cu" "B.Mask" "B.Paste")
			(net "M_E_DQS_DP<4>")
		)
		(pad "246" smd rect
			(at -4.59994 90.950034 270)
			(size 1.8034 0.508)
			(layers "B.Cu" "B.Mask" "B.Paste")
			(net "GND")
		)
	)
)
